(kicad_pcb
	(version 20241229)
	(generator "pcbnew")
	(generator_version "9.0")
	(general
		(thickness 1.599998)
		(legacy_teardrops no)
	)
	(paper "A4")
	(title_block
		(title "Artix - Datacenter Secure Control Module (DC-SCM)")
		(date "2024-11-06")
		(rev "1.1.3")
		(comment 9 "footprints 68-75 of 544")
	)
	(layers
		(0 "F.Cu" signal)
		(4 "In1.Cu" signal)
		(6 "In2.Cu" signal)
		(8 "In3.Cu" signal)
		(10 "In4.Cu" signal)
		(12 "In5.Cu" signal)
		(14 "In6.Cu" signal)
		(2 "B.Cu" signal)
		(9 "F.Adhes" user "F.Adhesive")
		(11 "B.Adhes" user "B.Adhesive")
		(13 "F.Paste" user)
		(15 "B.Paste" user)
		(5 "F.SilkS" user "F.Silkscreen")
		(7 "B.SilkS" user "B.Silkscreen")
		(1 "F.Mask" user)
		(3 "B.Mask" user)
		(17 "Dwgs.User" user "User.Drawings")
		(19 "Cmts.User" user "User.Comments")
		(21 "Eco1.User" user "User.Eco1")
		(23 "Eco2.User" user "User.Eco2")
		(25 "Edge.Cuts" user)
		(27 "Margin" user)
		(31 "F.CrtYd" user "F.Courtyard")
		(29 "B.CrtYd" user "B.Courtyard")
		(35 "F.Fab" user)
		(33 "B.Fab" user)
	)
	(footprint "antmicro-footprints:R_0402_1005Metric"
		(layer "F.Cu")
		(at 80.74 162.06 -90)
		(descr "Resistor SMD 0402")
		(tags "resistor SMD 0402")
		(property "Reference" "R51"
			(at -2.16 -8.36 90)
			(layer "F.SilkS")
			(effects
				(font
					(size 0.7 0.7)
					(thickness 0.15)
				)
				(justify right bottom)
			)
		)
		(property "Value" "R_357k_0402"
			(at 0 1.4 90)
			(layer "F.Fab")
			(effects
				(font
					(size 0.7 0.7)
					(thickness 0.15)
				)
				(justify right bottom)
			)
		)
		(property "Datasheet" "https://www.bourns.com/docs/product-datasheets/cr.pdf"
			(at 0 0 270)
			(layer "F.Fab")
			(hide yes)
			(effects
				(font
					(size 1.27 1.27)
					(thickness 0.15)
				)
			)
		)
		(property "Description" "SMD Chip Resistor"
			(at 0 0 270)
			(layer "F.Fab")
			(hide yes)
			(effects
				(font
					(size 1.27 1.27)
					(thickness 0.15)
				)
			)
		)
		(property "Author" "Antmicro"
			(at -81.32 242.8 0)
			(layer "F.Fab")
			(hide yes)
			(effects
				(font
					(size 1 1)
					(thickness 0.15)
				)
			)
		)
		(property "License" "Apache-2.0"
			(at -81.32 242.8 0)
			(layer "F.Fab")
			(hide yes)
			(effects
				(font
					(size 1 1)
					(thickness 0.15)
				)
			)
		)
		(property "MPN" "CR0402-FX-3573GLF"
			(at -81.32 242.8 0)
			(layer "F.Fab")
			(hide yes)
			(effects
				(font
					(size 1 1)
					(thickness 0.15)
				)
			)
		)
		(property "Manufacturer" "Bourns"
			(at -81.32 242.8 0)
			(layer "F.Fab")
			(hide yes)
			(effects
				(font
					(size 1 1)
					(thickness 0.15)
				)
			)
		)
		(property "Tolerance" "1%"
			(at -81.32 242.8 0)
			(layer "F.Fab")
			(hide yes)
			(effects
				(font
					(size 1 1)
					(thickness 0.15)
				)
			)
		)
		(property "Val" "357k"
			(at -81.32 242.8 0)
			(layer "F.Fab")
			(hide yes)
			(effects
				(font
					(size 1 1)
					(thickness 0.15)
				)
			)
		)
		(sheetname "/Interfaces/")
		(sheetfile "interfaces.kicad_sch")
		(attr smd)
		(fp_rect
			(start -0.925 -0.47)
			(end 0.925 0.47)
			(stroke
				(width 0.05)
				(type default)
			)
			(fill no)
			(layer "F.CrtYd")
		)
		(fp_rect
			(start -0.5 -0.25)
			(end 0.5 0.25)
			(stroke
				(width 0.15)
				(type solid)
			)
			(fill no)
			(layer "F.Fab")
		)
		(pad "1" smd roundrect
			(at -0.48 0 270)
			(size 0.59 0.64)
			(layers "F.Cu" "F.Mask" "F.Paste")
			(roundrect_rratio 0.25)
			(net 2 "VCC3V3")
			(pintype "passive")
		)
		(pad "2" smd roundrect
			(at 0.48 0 270)
			(size 0.59 0.64)
			(layers "F.Cu" "F.Mask" "F.Paste")
			(roundrect_rratio 0.25)
			(net 174 "I3C[3]_SDA_3V3")
			(pintype "passive")
		)
	)
	(footprint "antmicro-footprints:R_0402_1005Metric"
		(layer "F.Cu")
		(at 79.74 162.06 -90)
		(descr "Resistor SMD 0402")
		(tags "resistor SMD 0402")
		(property "Reference" "R52"
			(at -2.16 -8.36 90)
			(layer "F.SilkS")
			(effects
				(font
					(size 0.7 0.7)
					(thickness 0.15)
				)
				(justify right bottom)
			)
		)
		(property "Value" "R_357k_0402"
			(at 0 1.4 90)
			(layer "F.Fab")
			(effects
				(font
					(size 0.7 0.7)
					(thickness 0.15)
				)
				(justify right bottom)
			)
		)
		(property "Datasheet" "https://www.bourns.com/docs/product-datasheets/cr.pdf"
			(at 0 0 270)
			(layer "F.Fab")
			(hide yes)
			(effects
				(font
					(size 1.27 1.27)
					(thickness 0.15)
				)
			)
		)
		(property "Description" "SMD Chip Resistor"
			(at 0 0 270)
			(layer "F.Fab")
			(hide yes)
			(effects
				(font
					(size 1.27 1.27)
					(thickness 0.15)
				)
			)
		)
		(property "Author" "Antmicro"
			(at -82.32 241.8 0)
			(layer "F.Fab")
			(hide yes)
			(effects
				(font
					(size 1 1)
					(thickness 0.15)
				)
			)
		)
		(property "License" "Apache-2.0"
			(at -82.32 241.8 0)
			(layer "F.Fab")
			(hide yes)
			(effects
				(font
					(size 1 1)
					(thickness 0.15)
				)
			)
		)
		(property "MPN" "CR0402-FX-3573GLF"
			(at -82.32 241.8 0)
			(layer "F.Fab")
			(hide yes)
			(effects
				(font
					(size 1 1)
					(thickness 0.15)
				)
			)
		)
		(property "Manufacturer" "Bourns"
			(at -82.32 241.8 0)
			(layer "F.Fab")
			(hide yes)
			(effects
				(font
					(size 1 1)
					(thickness 0.15)
				)
			)
		)
		(property "Tolerance" "1%"
			(at -82.32 241.8 0)
			(layer "F.Fab")
			(hide yes)
			(effects
				(font
					(size 1 1)
					(thickness 0.15)
				)
			)
		)
		(property "Val" "357k"
			(at -82.32 241.8 0)
			(layer "F.Fab")
			(hide yes)
			(effects
				(font
					(size 1 1)
					(thickness 0.15)
				)
			)
		)
		(sheetname "/Interfaces/")
		(sheetfile "interfaces.kicad_sch")
		(attr smd)
		(fp_rect
			(start -0.925 -0.47)
			(end 0.925 0.47)
			(stroke
				(width 0.05)
				(type default)
			)
			(fill no)
			(layer "F.CrtYd")
		)
		(fp_rect
			(start -0.5 -0.25)
			(end 0.5 0.25)
			(stroke
				(width 0.15)
				(type solid)
			)
			(fill no)
			(layer "F.Fab")
		)
		(pad "1" smd roundrect
			(at -0.48 0 270)
			(size 0.59 0.64)
			(layers "F.Cu" "F.Mask" "F.Paste")
			(roundrect_rratio 0.25)
			(net 2 "VCC3V3")
			(pintype "passive")
		)
		(pad "2" smd roundrect
			(at 0.48 0 270)
			(size 0.59 0.64)
			(layers "F.Cu" "F.Mask" "F.Paste")
			(roundrect_rratio 0.25)
			(net 175 "I3C[3]_SCL_3V3")
			(pintype "passive")
		)
	)
	(footprint "antmicro-footprints:R_0402_1005Metric"
		(layer "F.Cu")
		(at 90.545 81.825 -90)
		(descr "Resistor SMD 0402")
		(tags "resistor SMD 0402")
		(property "Reference" "R77"
			(at -1.125 -4.455 90)
			(layer "F.SilkS")
			(effects
				(font
					(size 0.7 0.7)
					(thickness 0.15)
				)
				(justify right bottom)
			)
		)
		(property "Value" "R_66k5_0402"
			(at 0 1.4 90)
			(layer "F.Fab")
			(effects
				(font
					(size 0.7 0.7)
					(thickness 0.15)
				)
				(justify right bottom)
			)
		)
		(property "Datasheet" "https://www.bourns.com/docs/product-datasheets/cr.pdf"
			(at 0 0 270)
			(layer "F.Fab")
			(hide yes)
			(effects
				(font
					(size 1.27 1.27)
					(thickness 0.15)
				)
			)
		)
		(property "Description" "SMD Chip Resistor"
			(at 0 0 270)
			(layer "F.Fab")
			(hide yes)
			(effects
				(font
					(size 1.27 1.27)
					(thickness 0.15)
				)
			)
		)
		(property "Author" "Antmicro"
			(at 8.72 172.37 0)
			(layer "F.Fab")
			(hide yes)
			(effects
				(font
					(size 1 1)
					(thickness 0.15)
				)
			)
		)
		(property "License" "Apache-2.0"
			(at 8.72 172.37 0)
			(layer "F.Fab")
			(hide yes)
			(effects
				(font
					(size 1 1)
					(thickness 0.15)
				)
			)
		)
		(property "MPN" "CR0402-FX-6652GLF"
			(at 8.72 172.37 0)
			(layer "F.Fab")
			(hide yes)
			(effects
				(font
					(size 1 1)
					(thickness 0.15)
				)
			)
		)
		(property "Manufacturer" "Bourns"
			(at 8.72 172.37 0)
			(layer "F.Fab")
			(hide yes)
			(effects
				(font
					(size 1 1)
					(thickness 0.15)
				)
			)
		)
		(property "Tolerance" "1%"
			(at 8.72 172.37 0)
			(layer "F.Fab")
			(hide yes)
			(effects
				(font
					(size 1 1)
					(thickness 0.15)
				)
			)
		)
		(property "Val" "66k5"
			(at 8.72 172.37 0)
			(layer "F.Fab")
			(hide yes)
			(effects
				(font
					(size 1 1)
					(thickness 0.15)
				)
			)
		)
		(sheetname "/Power supply/")
		(sheetfile "power-supply.kicad_sch")
		(attr smd)
		(fp_rect
			(start -0.925 -0.47)
			(end 0.925 0.47)
			(stroke
				(width 0.05)
				(type default)
			)
			(fill no)
			(layer "F.CrtYd")
		)
		(fp_rect
			(start -0.5 -0.25)
			(end 0.5 0.25)
			(stroke
				(width 0.15)
				(type solid)
			)
			(fill no)
			(layer "F.Fab")
		)
		(pad "1" smd roundrect
			(at -0.48 0 270)
			(size 0.59 0.64)
			(layers "F.Cu" "F.Mask" "F.Paste")
			(roundrect_rratio 0.25)
			(net 276 "Net-(C81-Pad2)")
			(pintype "passive")
		)
		(pad "2" smd roundrect
			(at 0.48 0 270)
			(size 0.59 0.64)
			(layers "F.Cu" "F.Mask" "F.Paste")
			(roundrect_rratio 0.25)
			(net 195 "Net-(U12-FB)")
			(pintype "passive")
		)
	)
	(footprint "antmicro-footprints:R_0402_1005Metric"
		(layer "F.Cu")
		(at 110.474 166.675 90)
		(descr "Resistor SMD 0402")
		(tags "resistor SMD 0402")
		(property "Reference" "R136"
			(at -3.725 0.426 90)
			(layer "F.SilkS")
			(effects
				(font
					(size 0.7 0.7)
					(thickness 0.15)
				)
				(justify left bottom)
			)
		)
		(property "Value" "R_0R_0402"
			(at 0 1.4 90)
			(layer "F.Fab")
			(effects
				(font
					(size 0.7 0.7)
					(thickness 0.15)
				)
				(justify left bottom)
			)
		)
		(property "Datasheet" "https://industrial.panasonic.com/cdbs/www-data/pdf/RDA0000/AOA0000C301.pdf"
			(at 0 0 90)
			(layer "F.Fab")
			(hide yes)
			(effects
				(font
					(size 1.27 1.27)
					(thickness 0.15)
				)
			)
		)
		(property "Description" "SMD Chip Resistor, Jumper, 0 ohm, 100 mW, 0402 [1005 Metric], Thick Film, General Purpose"
			(at 0 0 90)
			(layer "F.Fab")
			(hide yes)
			(effects
				(font
					(size 1.27 1.27)
					(thickness 0.15)
				)
			)
		)
		(property "Author" "Antmicro"
			(at 277.149 56.201 0)
			(layer "F.Fab")
			(hide yes)
			(effects
				(font
					(size 1 1)
					(thickness 0.15)
				)
			)
		)
		(property "Current" "1A"
			(at 277.149 56.201 0)
			(layer "F.Fab")
			(hide yes)
			(effects
				(font
					(size 1 1)
					(thickness 0.15)
				)
			)
		)
		(property "License" "Apache-2.0"
			(at 277.149 56.201 0)
			(layer "F.Fab")
			(hide yes)
			(effects
				(font
					(size 1 1)
					(thickness 0.15)
				)
			)
		)
		(property "MPN" "ERJ2GE0R00X"
			(at 277.149 56.201 0)
			(layer "F.Fab")
			(hide yes)
			(effects
				(font
					(size 1 1)
					(thickness 0.15)
				)
			)
		)
		(property "Manufacturer" "Panasonic"
			(at 277.149 56.201 0)
			(layer "F.Fab")
			(hide yes)
			(effects
				(font
					(size 1 1)
					(thickness 0.15)
				)
			)
		)
		(property "Tolerance" "~"
			(at 277.149 56.201 0)
			(layer "F.Fab")
			(hide yes)
			(effects
				(font
					(size 1 1)
					(thickness 0.15)
				)
			)
		)
		(property "Val" "0R"
			(at 277.149 56.201 0)
			(layer "F.Fab")
			(hide yes)
			(effects
				(font
					(size 1 1)
					(thickness 0.15)
				)
			)
		)
		(sheetname "/Edge connector/")
		(sheetfile "edge-connector.kicad_sch")
		(attr smd)
		(fp_rect
			(start -0.925 -0.47)
			(end 0.925 0.47)
			(stroke
				(width 0.05)
				(type default)
			)
			(fill no)
			(layer "F.CrtYd")
		)
		(fp_rect
			(start -0.5 -0.25)
			(end 0.5 0.25)
			(stroke
				(width 0.15)
				(type solid)
			)
			(fill no)
			(layer "F.Fab")
		)
		(pad "1" smd roundrect
			(at -0.48 0 90)
			(size 0.59 0.64)
			(layers "F.Cu" "F.Mask" "F.Paste")
			(roundrect_rratio 0.25)
			(net 694 "Net-(J9-PadB35)")
			(pintype "passive")
		)
		(pad "2" smd roundrect
			(at 0.48 0 90)
			(size 0.59 0.64)
			(layers "F.Cu" "F.Mask" "F.Paste")
			(roundrect_rratio 0.25)
			(net 91 "RSVD2")
			(pintype "passive")
		)
	)
	(footprint "antmicro-footprints:R_0402_1005Metric"
		(layer "F.Cu")
		(at 109.374 166.675 -90)
		(descr "Resistor SMD 0402")
		(tags "resistor SMD 0402")
		(property "Reference" "R137"
			(at 0.925 -0.426 90)
			(layer "F.SilkS")
			(effects
				(font
					(size 0.7 0.7)
					(thickness 0.15)
				)
				(justify right bottom)
			)
		)
		(property "Value" "R_0R_0402"
			(at 0 1.4 90)
			(layer "F.Fab")
			(effects
				(font
					(size 0.7 0.7)
					(thickness 0.15)
				)
				(justify right bottom)
			)
		)
		(property "Datasheet" "https://industrial.panasonic.com/cdbs/www-data/pdf/RDA0000/AOA0000C301.pdf"
			(at 0 0 270)
			(layer "F.Fab")
			(hide yes)
			(effects
				(font
					(size 1.27 1.27)
					(thickness 0.15)
				)
			)
		)
		(property "Description" "SMD Chip Resistor, Jumper, 0 ohm, 100 mW, 0402 [1005 Metric], Thick Film, General Purpose"
			(at 0 0 270)
			(layer "F.Fab")
			(hide yes)
			(effects
				(font
					(size 1.27 1.27)
					(thickness 0.15)
				)
			)
		)
		(property "Author" "Antmicro"
			(at -57.301 276.049 0)
			(layer "F.Fab")
			(hide yes)
			(effects
				(font
					(size 1 1)
					(thickness 0.15)
				)
			)
		)
		(property "Current" "1A"
			(at -57.301 276.049 0)
			(layer "F.Fab")
			(hide yes)
			(effects
				(font
					(size 1 1)
					(thickness 0.15)
				)
			)
		)
		(property "License" "Apache-2.0"
			(at -57.301 276.049 0)
			(layer "F.Fab")
			(hide yes)
			(effects
				(font
					(size 1 1)
					(thickness 0.15)
				)
			)
		)
		(property "MPN" "ERJ2GE0R00X"
			(at -57.301 276.049 0)
			(layer "F.Fab")
			(hide yes)
			(effects
				(font
					(size 1 1)
					(thickness 0.15)
				)
			)
		)
		(property "Manufacturer" "Panasonic"
			(at -57.301 276.049 0)
			(layer "F.Fab")
			(hide yes)
			(effects
				(font
					(size 1 1)
					(thickness 0.15)
				)
			)
		)
		(property "Tolerance" "~"
			(at -57.301 276.049 0)
			(layer "F.Fab")
			(hide yes)
			(effects
				(font
					(size 1 1)
					(thickness 0.15)
				)
			)
		)
		(property "Val" "0R"
			(at -57.301 276.049 0)
			(layer "F.Fab")
			(hide yes)
			(effects
				(font
					(size 1 1)
					(thickness 0.15)
				)
			)
		)
		(sheetname "/Edge connector/")
		(sheetfile "edge-connector.kicad_sch")
		(attr smd)
		(fp_rect
			(start -0.925 -0.47)
			(end 0.925 0.47)
			(stroke
				(width 0.05)
				(type default)
			)
			(fill no)
			(layer "F.CrtYd")
		)
		(fp_rect
			(start -0.5 -0.25)
			(end 0.5 0.25)
			(stroke
				(width 0.15)
				(type solid)
			)
			(fill no)
			(layer "F.Fab")
		)
		(pad "1" smd roundrect
			(at -0.48 0 270)
			(size 0.59 0.64)
			(layers "F.Cu" "F.Mask" "F.Paste")
			(roundrect_rratio 0.25)
			(net 91 "RSVD2")
			(pintype "passive")
		)
		(pad "2" smd roundrect
			(at 0.48 0 270)
			(size 0.59 0.64)
			(layers "F.Cu" "F.Mask" "F.Paste")
			(roundrect_rratio 0.25)
			(net 87 "SGPIO0_CLK")
			(pintype "passive")
		)
	)
	(footprint "antmicro-footprints:TP_SMD_1mm"
		(layer "F.Cu")
		(at 64.335 84.240799)
		(property "Reference" "TP2"
			(at -2.635 0.259201 0)
			(layer "F.SilkS")
			(effects
				(font
					(size 0.7 0.7)
					(thickness 0.15)
				)
				(justify left bottom)
			)
		)
		(property "Value" "TP_1mm_SMD"
			(at 0 1.4 0)
			(layer "F.Fab")
			(effects
				(font
					(size 0.7 0.7)
					(thickness 0.15)
				)
				(justify left bottom)
			)
		)
		(property "Description" "Test point 1mm SMD"
			(at 0 0 0)
			(layer "F.Fab")
			(hide yes)
			(effects
				(font
					(size 1.27 1.27)
					(thickness 0.15)
				)
			)
		)
		(property "Author" "Antmicro"
			(at 0 0 0)
			(layer "F.Fab")
			(hide yes)
			(effects
				(font
					(size 1 1)
					(thickness 0.15)
				)
			)
		)
		(property "License" "Apache-2.0"
			(at 0 0 0)
			(layer "F.Fab")
			(hide yes)
			(effects
				(font
					(size 1 1)
					(thickness 0.15)
				)
			)
		)
		(property "MPN" ""
			(at 0 0 0)
			(layer "F.Fab")
			(hide yes)
			(effects
				(font
					(size 1 1)
					(thickness 0.15)
				)
			)
		)
		(property "Manufacturer" ""
			(at 0 0 0)
			(layer "F.Fab")
			(hide yes)
			(effects
				(font
					(size 1 1)
					(thickness 0.15)
				)
			)
		)
		(sheetname "/FPGA banks 34-35 & CFG/")
		(sheetfile "fpga-banks-34-25-cfg.kicad_sch")
		(attr exclude_from_pos_files exclude_from_bom)
		(fp_circle
			(center 0 0)
			(end 0.6 0)
			(stroke
				(width 0.05)
				(type default)
			)
			(fill no)
			(layer "F.CrtYd")
		)
		(pad "1" smd circle
			(at 0 0)
			(size 1 1)
			(layers "F.Cu" "F.Mask")
			(net 220 "DONE")
			(pinfunction "1")
			(pintype "passive")
		)
	)
	(footprint "antmicro-footprints:TP_SMD_1mm"
		(layer "F.Cu")
		(at 64.335 86.312899)
		(property "Reference" "TP5"
			(at -2.635 0.487101 0)
			(layer "F.SilkS")
			(effects
				(font
					(size 0.7 0.7)
					(thickness 0.15)
				)
				(justify left bottom)
			)
		)
		(property "Value" "TP_1mm_SMD"
			(at 0 1.4 0)
			(layer "F.Fab")
			(effects
				(font
					(size 0.7 0.7)
					(thickness 0.15)
				)
				(justify left bottom)
			)
		)
		(property "Description" "Test point 1mm SMD"
			(at 0 0 0)
			(layer "F.Fab")
			(hide yes)
			(effects
				(font
					(size 1.27 1.27)
					(thickness 0.15)
				)
			)
		)
		(property "Author" "Antmicro"
			(at 0 0 0)
			(layer "F.Fab")
			(hide yes)
			(effects
				(font
					(size 1 1)
					(thickness 0.15)
				)
			)
		)
		(property "License" "Apache-2.0"
			(at 0 0 0)
			(layer "F.Fab")
			(hide yes)
			(effects
				(font
					(size 1 1)
					(thickness 0.15)
				)
			)
		)
		(property "MPN" ""
			(at 0 0 0)
			(layer "F.Fab")
			(hide yes)
			(effects
				(font
					(size 1 1)
					(thickness 0.15)
				)
			)
		)
		(property "Manufacturer" ""
			(at 0 0 0)
			(layer "F.Fab")
			(hide yes)
			(effects
				(font
					(size 1 1)
					(thickness 0.15)
				)
			)
		)
		(sheetname "/FPGA banks 34-35 & CFG/")
		(sheetfile "fpga-banks-34-25-cfg.kicad_sch")
		(attr exclude_from_pos_files exclude_from_bom)
		(fp_circle
			(center 0 0)
			(end 0.6 0)
			(stroke
				(width 0.05)
				(type default)
			)
			(fill no)
			(layer "F.CrtYd")
		)
		(pad "1" smd circle
			(at 0 0)
			(size 1 1)
			(layers "F.Cu" "F.Mask")
			(net 222 "INIT")
			(pinfunction "1")
			(pintype "passive")
		)
	)
	(footprint "antmicro-footprints:TP_SMD_1mm"
		(layer "F.Cu")
		(at 64.335 88.385)
		(property "Reference" "TP6"
			(at -2.635 0.415 0)
			(layer "F.SilkS")
			(effects
				(font
					(size 0.7 0.7)
					(thickness 0.15)
				)
				(justify left bottom)
			)
		)
		(property "Value" "TP_1mm_SMD"
			(at 0 1.4 0)
			(layer "F.Fab")
			(effects
				(font
					(size 0.7 0.7)
					(thickness 0.15)
				)
				(justify left bottom)
			)
		)
		(property "Description" "Test point 1mm SMD"
			(at 0 0 0)
			(layer "F.Fab")
			(hide yes)
			(effects
				(font
					(size 1.27 1.27)
					(thickness 0.15)
				)
			)
		)
		(property "Author" "Antmicro"
			(at 0 0 0)
			(layer "F.Fab")
			(hide yes)
			(effects
				(font
					(size 1 1)
					(thickness 0.15)
				)
			)
		)
		(property "License" "Apache-2.0"
			(at 0 0 0)
			(layer "F.Fab")
			(hide yes)
			(effects
				(font
					(size 1 1)
					(thickness 0.15)
				)
			)
		)
		(property "MPN" ""
			(at 0 0 0)
			(layer "F.Fab")
			(hide yes)
			(effects
				(font
					(size 1 1)
					(thickness 0.15)
				)
			)
		)
		(property "Manufacturer" ""
			(at 0 0 0)
			(layer "F.Fab")
			(hide yes)
			(effects
				(font
					(size 1 1)
					(thickness 0.15)
				)
			)
		)
		(sheetname "/FPGA banks 34-35 & CFG/")
		(sheetfile "fpga-banks-34-25-cfg.kicad_sch")
		(attr exclude_from_pos_files exclude_from_bom)
		(fp_circle
			(center 0 0)
			(end 0.6 0)
			(stroke
				(width 0.05)
				(type default)
			)
			(fill no)
			(layer "F.CrtYd")
		)
		(pad "1" smd circle
			(at 0 0)
			(size 1 1)
			(layers "F.Cu" "F.Mask")
			(net 221 "PROGRAM")
			(pinfunction "1")
			(pintype "passive")
		)
	)
)
